G04 ================== begin FILE IDENTIFICATION RECORD ==================*
G04 Layout Name:  15105-sa.brd*
G04 Film Name:    GOLD_B*
G04 File Format:  Gerber RS274X*
G04 File Origin:  Cadence Allegro 16.5-S056*
G04 Origin Date:  Wed Nov 16 02:02:09 2016*
G04 *
G04 Layer:  PACKAGE GEOMETRY/GOLDEN_BOTTOM*
G04 Layer:  DRAWING FORMAT/LAYER_GOLD_B*
G04 Layer:  DRAWING FORMAT/LAYER_PCB_STORY*
G04 Layer:  BOARD GEOMETRY/GOLDEN_BOTTOM*
G04 Layer:  BOARD GEOMETRY/PANEL_OUTLINE*
G04 *
G04 Offset:    (0.00 0.00)*
G04 Mirror:    No*
G04 Mode:      Positive*
G04 Rotation:  0*
G04 FullContactRelief:  No*
G04 UndefLineWidth:     6.00*
G04 ================== end FILE IDENTIFICATION RECORD ====================*
%FSLAX35Y35*MOIN*%
%IR0*IPPOS*OFA0.00000B0.00000*MIA0B0*SFA1.00000B1.00000*%
%ADD10C,.02*%
%ADD11C,.006*%
G75*
%LPD*%
G75*
G36*
G01X116455Y892520D02*
X114255D01*
Y883420D01*
X116455D01*
Y892520D01*
G37*
G36*
G01X119604D02*
X117404D01*
Y883420D01*
X119604D01*
Y892520D01*
G37*
G36*
G01X122754D02*
X120554D01*
Y883420D01*
X122754D01*
Y892520D01*
G37*
G36*
G01X125903D02*
X123703D01*
Y883420D01*
X125903D01*
Y892520D01*
G37*
G36*
G01X129053D02*
X126853D01*
Y883420D01*
X129053D01*
Y892520D01*
G37*
G36*
G01X132203D02*
X130003D01*
Y883420D01*
X132203D01*
Y892520D01*
G37*
G36*
G01X135352D02*
X133152D01*
Y883420D01*
X135352D01*
Y892520D01*
G37*
G36*
G01X138502D02*
X136302D01*
Y883420D01*
X138502D01*
Y892520D01*
G37*
G36*
G01X141651D02*
X139451D01*
Y883420D01*
X141651D01*
Y892520D01*
G37*
G36*
G01X144801D02*
X142601D01*
Y883420D01*
X144801D01*
Y892520D01*
G37*
G36*
G01X147951D02*
X145751D01*
Y883420D01*
X147951D01*
Y892520D01*
G37*
G36*
G01X151100D02*
X148900D01*
Y883420D01*
X151100D01*
Y892520D01*
G37*
G36*
G01X154250D02*
X152050D01*
Y883420D01*
X154250D01*
Y892520D01*
G37*
G36*
G01X157400D02*
X155200D01*
Y883420D01*
X157400D01*
Y892520D01*
G37*
G36*
G01X160549D02*
X158349D01*
Y883420D01*
X160549D01*
Y892520D01*
G37*
G36*
G01X163699D02*
X161499D01*
Y883420D01*
X163699D01*
Y892520D01*
G37*
G36*
G01X166848D02*
X164648D01*
Y883420D01*
X166848D01*
Y892520D01*
G37*
G36*
G01X169998D02*
X167798D01*
Y883420D01*
X169998D01*
Y892520D01*
G37*
G36*
G01X173148D02*
X170948D01*
Y883420D01*
X173148D01*
Y892520D01*
G37*
G36*
G01X176297D02*
X174097D01*
Y883420D01*
X176297D01*
Y892520D01*
G37*
G36*
G01X179447D02*
X177247D01*
Y883420D01*
X179447D01*
Y892520D01*
G37*
G36*
G01X182596D02*
X180396D01*
Y883420D01*
X182596D01*
Y892520D01*
G37*
G36*
G01X185746D02*
X183546D01*
Y883420D01*
X185746D01*
Y892520D01*
G37*
G36*
G01X188896D02*
X186696D01*
Y883420D01*
X188896D01*
Y892520D01*
G37*
G36*
G01X192045D02*
X189845D01*
Y883420D01*
X192045D01*
Y892520D01*
G37*
G36*
G01X195195D02*
X192995D01*
Y883420D01*
X195195D01*
Y892520D01*
G37*
G36*
G01X198344D02*
X196144D01*
Y883420D01*
X198344D01*
Y892520D01*
G37*
G36*
G01X201494D02*
X199294D01*
Y883420D01*
X201494D01*
Y892520D01*
G37*
G36*
G01X204644D02*
X202444D01*
Y883420D01*
X204644D01*
Y892520D01*
G37*
G36*
G01X207793D02*
X205593D01*
Y883420D01*
X207793D01*
Y892520D01*
G37*
G36*
G01X210943D02*
X208743D01*
Y883420D01*
X210943D01*
Y892520D01*
G37*
G36*
G01X214092D02*
X211892D01*
Y883420D01*
X214092D01*
Y892520D01*
G37*
G36*
G01X217242D02*
X215042D01*
Y883420D01*
X217242D01*
Y892520D01*
G37*
G36*
G01X220392D02*
X218192D01*
Y883420D01*
X220392D01*
Y892520D01*
G37*
G36*
G01X223541D02*
X221341D01*
Y883420D01*
X223541D01*
Y892520D01*
G37*
G36*
G01X226691D02*
X224491D01*
Y883420D01*
X226691D01*
Y892520D01*
G37*
G36*
G01X229840D02*
X227640D01*
Y883420D01*
X229840D01*
Y892520D01*
G37*
G36*
G01X232990D02*
X230790D01*
Y883420D01*
X232990D01*
Y892520D01*
G37*
G36*
G01X236140D02*
X233940D01*
Y883420D01*
X236140D01*
Y892520D01*
G37*
G36*
G01X239289D02*
X237089D01*
Y883420D01*
X239289D01*
Y892520D01*
G37*
G36*
G01X242439D02*
X240239D01*
Y883420D01*
X242439D01*
Y892520D01*
G37*
G36*
G01X245588D02*
X243388D01*
Y883420D01*
X245588D01*
Y892520D01*
G37*
G36*
G01X248738D02*
X246538D01*
Y883420D01*
X248738D01*
Y892520D01*
G37*
G36*
G01X251888D02*
X249688D01*
Y883420D01*
X251888D01*
Y892520D01*
G37*
G36*
G01X255037D02*
X252837D01*
Y883420D01*
X255037D01*
Y892520D01*
G37*
G36*
G01X258187D02*
X255987D01*
Y883420D01*
X258187D01*
Y892520D01*
G37*
G36*
G01X261337D02*
X259137D01*
Y883420D01*
X261337D01*
Y892520D01*
G37*
G36*
G01X264486D02*
X262286D01*
Y883420D01*
X264486D01*
Y892520D01*
G37*
G36*
G01X267636D02*
X265436D01*
Y883420D01*
X267636D01*
Y892520D01*
G37*
G36*
G01X270785D02*
X268585D01*
Y883420D01*
X270785D01*
Y892520D01*
G37*
G36*
G01X273935D02*
X271735D01*
Y883420D01*
X273935D01*
Y892520D01*
G37*
G36*
G01X277085D02*
X274885D01*
Y883420D01*
X277085D01*
Y892520D01*
G37*
G36*
G01X280234D02*
X278034D01*
Y883420D01*
X280234D01*
Y892520D01*
G37*
G36*
G01X283384D02*
X281184D01*
Y883420D01*
X283384D01*
Y892520D01*
G37*
G36*
G01X286533D02*
X284333D01*
Y883420D01*
X286533D01*
Y892520D01*
G37*
G36*
G01X289683D02*
X287483D01*
Y883420D01*
X289683D01*
Y892520D01*
G37*
G36*
G01X305431D02*
X303231D01*
Y883420D01*
X305431D01*
Y892520D01*
G37*
G36*
G01X308581D02*
X306381D01*
Y883420D01*
X308581D01*
Y892520D01*
G37*
G36*
G01X311730D02*
X309530D01*
Y883420D01*
X311730D01*
Y892520D01*
G37*
G36*
G01X314880D02*
X312680D01*
Y883420D01*
X314880D01*
Y892520D01*
G37*
G36*
G01X318029D02*
X315829D01*
Y883420D01*
X318029D01*
Y892520D01*
G37*
G36*
G01X321179D02*
X318979D01*
Y883420D01*
X321179D01*
Y892520D01*
G37*
G36*
G01X324329D02*
X322129D01*
Y883420D01*
X324329D01*
Y892520D01*
G37*
G36*
G01X327478D02*
X325278D01*
Y883420D01*
X327478D01*
Y892520D01*
G37*
G36*
G01X330628D02*
X328428D01*
Y883420D01*
X330628D01*
Y892520D01*
G37*
G36*
G01X333777D02*
X331577D01*
Y883420D01*
X333777D01*
Y892520D01*
G37*
G36*
G01X336927D02*
X334727D01*
Y883420D01*
X336927D01*
Y892520D01*
G37*
G36*
G01X340077D02*
X337877D01*
Y883420D01*
X340077D01*
Y892520D01*
G37*
G36*
G01X343226D02*
X341026D01*
Y883420D01*
X343226D01*
Y892520D01*
G37*
G36*
G01X346376D02*
X344176D01*
Y883420D01*
X346376D01*
Y892520D01*
G37*
G36*
G01X349526D02*
X347326D01*
Y883420D01*
X349526D01*
Y892520D01*
G37*
G36*
G01X352675D02*
X350475D01*
Y883420D01*
X352675D01*
Y892520D01*
G37*
G36*
G01X355825D02*
X353625D01*
Y883420D01*
X355825D01*
Y892520D01*
G37*
G36*
G01X358974D02*
X356774D01*
Y883420D01*
X358974D01*
Y892520D01*
G37*
G36*
G01X362124D02*
X359924D01*
Y883420D01*
X362124D01*
Y892520D01*
G37*
G36*
G01X365274D02*
X363074D01*
Y883420D01*
X365274D01*
Y892520D01*
G37*
G36*
G01X368423D02*
X366223D01*
Y883420D01*
X368423D01*
Y892520D01*
G37*
G36*
G01X371573D02*
X369373D01*
Y883420D01*
X371573D01*
Y892520D01*
G37*
G36*
G01X374722D02*
X372522D01*
Y883420D01*
X374722D01*
Y892520D01*
G37*
G36*
G01X377872D02*
X375672D01*
Y883420D01*
X377872D01*
Y892520D01*
G37*
G36*
G01X381022D02*
X378822D01*
Y883420D01*
X381022D01*
Y892520D01*
G37*
G36*
G01X384171D02*
X381971D01*
Y883420D01*
X384171D01*
Y892520D01*
G37*
G36*
G01X387321D02*
X385121D01*
Y883420D01*
X387321D01*
Y892520D01*
G37*
G36*
G01X390470D02*
X388270D01*
Y883420D01*
X390470D01*
Y892520D01*
G37*
G36*
G01X393620D02*
X391420D01*
Y883420D01*
X393620D01*
Y892520D01*
G37*
G36*
G01X396770D02*
X394570D01*
Y883420D01*
X396770D01*
Y892520D01*
G37*
G36*
G01X399919D02*
X397719D01*
Y883420D01*
X399919D01*
Y892520D01*
G37*
G36*
G01X403069D02*
X400869D01*
Y883420D01*
X403069D01*
Y892520D01*
G37*
G36*
G01X406218D02*
X404018D01*
Y883420D01*
X406218D01*
Y892520D01*
G37*
G36*
G01X409368D02*
X407168D01*
Y883420D01*
X409368D01*
Y892520D01*
G37*
G36*
G01X412518D02*
X410318D01*
Y883420D01*
X412518D01*
Y892520D01*
G37*
G36*
G01X415667D02*
X413467D01*
Y883420D01*
X415667D01*
Y892520D01*
G37*
G36*
G01X418817D02*
X416617D01*
Y883420D01*
X418817D01*
Y892520D01*
G37*
G36*
G01X421966D02*
X419766D01*
Y883420D01*
X421966D01*
Y892520D01*
G37*
G36*
G01X425116D02*
X422916D01*
Y883420D01*
X425116D01*
Y892520D01*
G37*
G36*
G01X428266D02*
X426066D01*
Y883420D01*
X428266D01*
Y892520D01*
G37*
G36*
G01X431415D02*
X429215D01*
Y883420D01*
X431415D01*
Y892520D01*
G37*
G36*
G01X434565D02*
X432365D01*
Y883420D01*
X434565D01*
Y892520D01*
G37*
G36*
G01X437714D02*
X435514D01*
Y883420D01*
X437714D01*
Y892520D01*
G37*
G36*
G01X440864D02*
X438664D01*
Y883420D01*
X440864D01*
Y892520D01*
G37*
G36*
G01X533778D02*
X531578D01*
Y883420D01*
X533778D01*
Y892520D01*
G37*
G36*
G01X536927D02*
X534727D01*
Y883420D01*
X536927D01*
Y892520D01*
G37*
G36*
G01X540077D02*
X537877D01*
Y883420D01*
X540077D01*
Y892520D01*
G37*
G36*
G01X543226D02*
X541026D01*
Y883420D01*
X543226D01*
Y892520D01*
G37*
G36*
G01X546376D02*
X544176D01*
Y883420D01*
X546376D01*
Y892520D01*
G37*
G36*
G01X549526D02*
X547326D01*
Y883420D01*
X549526D01*
Y892520D01*
G37*
G36*
G01X552675D02*
X550475D01*
Y883420D01*
X552675D01*
Y892520D01*
G37*
G36*
G01X555825D02*
X553625D01*
Y883420D01*
X555825D01*
Y892520D01*
G37*
G36*
G01X558974D02*
X556774D01*
Y883420D01*
X558974D01*
Y892520D01*
G37*
G36*
G01X562124D02*
X559924D01*
Y883420D01*
X562124D01*
Y892520D01*
G37*
G36*
G01X565274D02*
X563074D01*
Y883420D01*
X565274D01*
Y892520D01*
G37*
G36*
G01X568423D02*
X566223D01*
Y883420D01*
X568423D01*
Y892520D01*
G37*
G36*
G01X571573D02*
X569373D01*
Y883420D01*
X571573D01*
Y892520D01*
G37*
G36*
G01X574723D02*
X572523D01*
Y883420D01*
X574723D01*
Y892520D01*
G37*
G36*
G01X577872D02*
X575672D01*
Y883420D01*
X577872D01*
Y892520D01*
G37*
G36*
G01X581022D02*
X578822D01*
Y883420D01*
X581022D01*
Y892520D01*
G37*
G36*
G01X584171D02*
X581971D01*
Y883420D01*
X584171D01*
Y892520D01*
G37*
G36*
G01X587321D02*
X585121D01*
Y883420D01*
X587321D01*
Y892520D01*
G37*
G36*
G01X590471D02*
X588271D01*
Y883420D01*
X590471D01*
Y892520D01*
G37*
G36*
G01X593620D02*
X591420D01*
Y883420D01*
X593620D01*
Y892520D01*
G37*
G36*
G01X596770D02*
X594570D01*
Y883420D01*
X596770D01*
Y892520D01*
G37*
G36*
G01X599919D02*
X597719D01*
Y883420D01*
X599919D01*
Y892520D01*
G37*
G36*
G01X603069D02*
X600869D01*
Y883420D01*
X603069D01*
Y892520D01*
G37*
G36*
G01X606219D02*
X604019D01*
Y883420D01*
X606219D01*
Y892520D01*
G37*
G36*
G01X609368D02*
X607168D01*
Y883420D01*
X609368D01*
Y892520D01*
G37*
G36*
G01X612518D02*
X610318D01*
Y883420D01*
X612518D01*
Y892520D01*
G37*
G36*
G01X615667D02*
X613467D01*
Y883420D01*
X615667D01*
Y892520D01*
G37*
G36*
G01X618817D02*
X616617D01*
Y883420D01*
X618817D01*
Y892520D01*
G37*
G36*
G01X621967D02*
X619767D01*
Y883420D01*
X621967D01*
Y892520D01*
G37*
G36*
G01X625116D02*
X622916D01*
Y883420D01*
X625116D01*
Y892520D01*
G37*
G36*
G01X628266D02*
X626066D01*
Y883420D01*
X628266D01*
Y892520D01*
G37*
G36*
G01X631415D02*
X629215D01*
Y883420D01*
X631415D01*
Y892520D01*
G37*
G36*
G01X634565D02*
X632365D01*
Y883420D01*
X634565D01*
Y892520D01*
G37*
G36*
G01X637715D02*
X635515D01*
Y883420D01*
X637715D01*
Y892520D01*
G37*
G36*
G01X640864D02*
X638664D01*
Y883420D01*
X640864D01*
Y892520D01*
G37*
G36*
G01X644014D02*
X641814D01*
Y883420D01*
X644014D01*
Y892520D01*
G37*
G36*
G01X647163D02*
X644963D01*
Y883420D01*
X647163D01*
Y892520D01*
G37*
G36*
G01X650313D02*
X648113D01*
Y883420D01*
X650313D01*
Y892520D01*
G37*
G36*
G01X653463D02*
X651263D01*
Y883420D01*
X653463D01*
Y892520D01*
G37*
G36*
G01X656612D02*
X654412D01*
Y883420D01*
X656612D01*
Y892520D01*
G37*
G36*
G01X659762D02*
X657562D01*
Y883420D01*
X659762D01*
Y892520D01*
G37*
G36*
G01X662911D02*
X660711D01*
Y883420D01*
X662911D01*
Y892520D01*
G37*
G36*
G01X666061D02*
X663861D01*
Y883420D01*
X666061D01*
Y892520D01*
G37*
G36*
G01X669211D02*
X667011D01*
Y883420D01*
X669211D01*
Y892520D01*
G37*
G36*
G01X672360D02*
X670160D01*
Y883420D01*
X672360D01*
Y892520D01*
G37*
G36*
G01X675510D02*
X673310D01*
Y883420D01*
X675510D01*
Y892520D01*
G37*
G36*
G01X678660D02*
X676460D01*
Y883420D01*
X678660D01*
Y892520D01*
G37*
G36*
G01X681809D02*
X679609D01*
Y883420D01*
X681809D01*
Y892520D01*
G37*
G36*
G01X684959D02*
X682759D01*
Y883420D01*
X684959D01*
Y892520D01*
G37*
G36*
G01X688108D02*
X685908D01*
Y883420D01*
X688108D01*
Y892520D01*
G37*
G36*
G01X691258D02*
X689058D01*
Y883420D01*
X691258D01*
Y892520D01*
G37*
G36*
G01X694408D02*
X692208D01*
Y883420D01*
X694408D01*
Y892520D01*
G37*
G36*
G01X697557D02*
X695357D01*
Y883420D01*
X697557D01*
Y892520D01*
G37*
G36*
G01X700707D02*
X698507D01*
Y883420D01*
X700707D01*
Y892520D01*
G37*
G36*
G01X703856D02*
X701656D01*
Y883420D01*
X703856D01*
Y892520D01*
G37*
G36*
G01X707006D02*
X704806D01*
Y883420D01*
X707006D01*
Y892520D01*
G37*
G36*
G01X722754D02*
X720554D01*
Y883420D01*
X722754D01*
Y892520D01*
G37*
G36*
G01X725904D02*
X723704D01*
Y883420D01*
X725904D01*
Y892520D01*
G37*
G36*
G01X729053D02*
X726853D01*
Y883420D01*
X729053D01*
Y892520D01*
G37*
G36*
G01X732203D02*
X730003D01*
Y883420D01*
X732203D01*
Y892520D01*
G37*
G36*
G01X735352D02*
X733152D01*
Y883420D01*
X735352D01*
Y892520D01*
G37*
G36*
G01X738502D02*
X736302D01*
Y883420D01*
X738502D01*
Y892520D01*
G37*
G36*
G01X741652D02*
X739452D01*
Y883420D01*
X741652D01*
Y892520D01*
G37*
G36*
G01X744801D02*
X742601D01*
Y883420D01*
X744801D01*
Y892520D01*
G37*
G36*
G01X747951D02*
X745751D01*
Y883420D01*
X747951D01*
Y892520D01*
G37*
G36*
G01X751100D02*
X748900D01*
Y883420D01*
X751100D01*
Y892520D01*
G37*
G36*
G01X754250D02*
X752050D01*
Y883420D01*
X754250D01*
Y892520D01*
G37*
G36*
G01X757400D02*
X755200D01*
Y883420D01*
X757400D01*
Y892520D01*
G37*
G36*
G01X760549D02*
X758349D01*
Y883420D01*
X760549D01*
Y892520D01*
G37*
G36*
G01X763699D02*
X761499D01*
Y883420D01*
X763699D01*
Y892520D01*
G37*
G36*
G01X766849D02*
X764649D01*
Y883420D01*
X766849D01*
Y892520D01*
G37*
G36*
G01X769998D02*
X767798D01*
Y883420D01*
X769998D01*
Y892520D01*
G37*
G36*
G01X773148D02*
X770948D01*
Y883420D01*
X773148D01*
Y892520D01*
G37*
G36*
G01X776297D02*
X774097D01*
Y883420D01*
X776297D01*
Y892520D01*
G37*
G36*
G01X779447D02*
X777247D01*
Y883420D01*
X779447D01*
Y892520D01*
G37*
G36*
G01X782597D02*
X780397D01*
Y883420D01*
X782597D01*
Y892520D01*
G37*
G36*
G01X785746D02*
X783546D01*
Y883420D01*
X785746D01*
Y892520D01*
G37*
G36*
G01X788896D02*
X786696D01*
Y883420D01*
X788896D01*
Y892520D01*
G37*
G36*
G01X792045D02*
X789845D01*
Y883420D01*
X792045D01*
Y892520D01*
G37*
G36*
G01X795195D02*
X792995D01*
Y883420D01*
X795195D01*
Y892520D01*
G37*
G36*
G01X798345D02*
X796145D01*
Y883420D01*
X798345D01*
Y892520D01*
G37*
G36*
G01X801494D02*
X799294D01*
Y883420D01*
X801494D01*
Y892520D01*
G37*
G36*
G01X804644D02*
X802444D01*
Y883420D01*
X804644D01*
Y892520D01*
G37*
G36*
G01X807793D02*
X805593D01*
Y883420D01*
X807793D01*
Y892520D01*
G37*
G36*
G01X810943D02*
X808743D01*
Y883420D01*
X810943D01*
Y892520D01*
G37*
G36*
G01X814093D02*
X811893D01*
Y883420D01*
X814093D01*
Y892520D01*
G37*
G36*
G01X817242D02*
X815042D01*
Y883420D01*
X817242D01*
Y892520D01*
G37*
G36*
G01X820392D02*
X818192D01*
Y883420D01*
X820392D01*
Y892520D01*
G37*
G36*
G01X823541D02*
X821341D01*
Y883420D01*
X823541D01*
Y892520D01*
G37*
G36*
G01X826691D02*
X824491D01*
Y883420D01*
X826691D01*
Y892520D01*
G37*
G36*
G01X829841D02*
X827641D01*
Y883420D01*
X829841D01*
Y892520D01*
G37*
G36*
G01X832990D02*
X830790D01*
Y883420D01*
X832990D01*
Y892520D01*
G37*
G36*
G01X836140D02*
X833940D01*
Y883420D01*
X836140D01*
Y892520D01*
G37*
G36*
G01X839289D02*
X837089D01*
Y883420D01*
X839289D01*
Y892520D01*
G37*
G36*
G01X842439D02*
X840239D01*
Y883420D01*
X842439D01*
Y892520D01*
G37*
G36*
G01X845589D02*
X843389D01*
Y883420D01*
X845589D01*
Y892520D01*
G37*
G36*
G01X848738D02*
X846538D01*
Y883420D01*
X848738D01*
Y892520D01*
G37*
G36*
G01X851888D02*
X849688D01*
Y883420D01*
X851888D01*
Y892520D01*
G37*
G36*
G01X855037D02*
X852837D01*
Y883420D01*
X855037D01*
Y892520D01*
G37*
G36*
G01X858187D02*
X855987D01*
Y883420D01*
X858187D01*
Y892520D01*
G37*
G36*
G01X1029841D02*
X1027641D01*
Y883420D01*
X1029841D01*
Y892520D01*
G37*
G36*
G01X1032990D02*
X1030790D01*
Y883420D01*
X1032990D01*
Y892520D01*
G37*
G36*
G01X1036140D02*
X1033940D01*
Y883420D01*
X1036140D01*
Y892520D01*
G37*
G36*
G01X1039289D02*
X1037089D01*
Y883420D01*
X1039289D01*
Y892520D01*
G37*
G36*
G01X1042439D02*
X1040239D01*
Y883420D01*
X1042439D01*
Y892520D01*
G37*
G36*
G01X1045589D02*
X1043389D01*
Y883420D01*
X1045589D01*
Y892520D01*
G37*
G36*
G01X1048738D02*
X1046538D01*
Y883420D01*
X1048738D01*
Y892520D01*
G37*
G36*
G01X1051888D02*
X1049688D01*
Y883420D01*
X1051888D01*
Y892520D01*
G37*
G36*
G01X1055037D02*
X1052837D01*
Y883420D01*
X1055037D01*
Y892520D01*
G37*
G36*
G01X1058187D02*
X1055987D01*
Y883420D01*
X1058187D01*
Y892520D01*
G37*
G36*
G01X1061337D02*
X1059137D01*
Y883420D01*
X1061337D01*
Y892520D01*
G37*
G36*
G01X1064486D02*
X1062286D01*
Y883420D01*
X1064486D01*
Y892520D01*
G37*
G36*
G01X1067636D02*
X1065436D01*
Y883420D01*
X1067636D01*
Y892520D01*
G37*
G36*
G01X1070786D02*
X1068586D01*
Y883420D01*
X1070786D01*
Y892520D01*
G37*
G36*
G01X1073935D02*
X1071735D01*
Y883420D01*
X1073935D01*
Y892520D01*
G37*
G36*
G01X1077085D02*
X1074885D01*
Y883420D01*
X1077085D01*
Y892520D01*
G37*
G36*
G01X1080234D02*
X1078034D01*
Y883420D01*
X1080234D01*
Y892520D01*
G37*
G36*
G01X1083384D02*
X1081184D01*
Y883420D01*
X1083384D01*
Y892520D01*
G37*
G36*
G01X1086534D02*
X1084334D01*
Y883420D01*
X1086534D01*
Y892520D01*
G37*
G36*
G01X1089683D02*
X1087483D01*
Y883420D01*
X1089683D01*
Y892520D01*
G37*
G36*
G01X1092833D02*
X1090633D01*
Y883420D01*
X1092833D01*
Y892520D01*
G37*
G36*
G01X1095982D02*
X1093782D01*
Y883420D01*
X1095982D01*
Y892520D01*
G37*
G36*
G01X1099132D02*
X1096932D01*
Y883420D01*
X1099132D01*
Y892520D01*
G37*
G36*
G01X1102282D02*
X1100082D01*
Y883420D01*
X1102282D01*
Y892520D01*
G37*
G36*
G01X1105431D02*
X1103231D01*
Y883420D01*
X1105431D01*
Y892520D01*
G37*
G36*
G01X1108581D02*
X1106381D01*
Y883420D01*
X1108581D01*
Y892520D01*
G37*
G36*
G01X1111730D02*
X1109530D01*
Y883420D01*
X1111730D01*
Y892520D01*
G37*
G36*
G01X1114880D02*
X1112680D01*
Y883420D01*
X1114880D01*
Y892520D01*
G37*
G36*
G01X1118030D02*
X1115830D01*
Y883420D01*
X1118030D01*
Y892520D01*
G37*
G36*
G01X1121179D02*
X1118979D01*
Y883420D01*
X1121179D01*
Y892520D01*
G37*
G36*
G01X1124329D02*
X1122129D01*
Y883420D01*
X1124329D01*
Y892520D01*
G37*
G36*
G01X1127478D02*
X1125278D01*
Y883420D01*
X1127478D01*
Y892520D01*
G37*
G36*
G01X1130628D02*
X1128428D01*
Y883420D01*
X1130628D01*
Y892520D01*
G37*
G36*
G01X1133778D02*
X1131578D01*
Y883420D01*
X1133778D01*
Y892520D01*
G37*
G36*
G01X1136927D02*
X1134727D01*
Y883420D01*
X1136927D01*
Y892520D01*
G37*
G36*
G01X1140077D02*
X1137877D01*
Y883420D01*
X1140077D01*
Y892520D01*
G37*
G36*
G01X1143226D02*
X1141026D01*
Y883420D01*
X1143226D01*
Y892520D01*
G37*
G36*
G01X1146376D02*
X1144176D01*
Y883420D01*
X1146376D01*
Y892520D01*
G37*
G36*
G01X1149526D02*
X1147326D01*
Y883420D01*
X1149526D01*
Y892520D01*
G37*
G36*
G01X1152675D02*
X1150475D01*
Y883420D01*
X1152675D01*
Y892520D01*
G37*
G36*
G01X1155825D02*
X1153625D01*
Y883420D01*
X1155825D01*
Y892520D01*
G37*
G36*
G01X1158974D02*
X1156774D01*
Y883420D01*
X1158974D01*
Y892520D01*
G37*
G36*
G01X1162124D02*
X1159924D01*
Y883420D01*
X1162124D01*
Y892520D01*
G37*
G36*
G01X1165274D02*
X1163074D01*
Y883420D01*
X1165274D01*
Y892520D01*
G37*
G36*
G01X1168423D02*
X1166223D01*
Y883420D01*
X1168423D01*
Y892520D01*
G37*
G36*
G01X1171573D02*
X1169373D01*
Y883420D01*
X1171573D01*
Y892520D01*
G37*
G36*
G01X1174723D02*
X1172523D01*
Y883420D01*
X1174723D01*
Y892520D01*
G37*
G36*
G01X1177872D02*
X1175672D01*
Y883420D01*
X1177872D01*
Y892520D01*
G37*
G36*
G01X1181022D02*
X1178822D01*
Y883420D01*
X1181022D01*
Y892520D01*
G37*
G36*
G01X1184171D02*
X1181971D01*
Y883420D01*
X1184171D01*
Y892520D01*
G37*
G36*
G01X1187321D02*
X1185121D01*
Y883420D01*
X1187321D01*
Y892520D01*
G37*
G36*
G01X1190471D02*
X1188271D01*
Y883420D01*
X1190471D01*
Y892520D01*
G37*
G36*
G01X1193620D02*
X1191420D01*
Y883420D01*
X1193620D01*
Y892520D01*
G37*
G36*
G01X1196770D02*
X1194570D01*
Y883420D01*
X1196770D01*
Y892520D01*
G37*
G36*
G01X1199919D02*
X1197719D01*
Y883420D01*
X1199919D01*
Y892520D01*
G37*
G36*
G01X1203069D02*
X1200869D01*
Y883420D01*
X1203069D01*
Y892520D01*
G37*
G36*
G01X1218817D02*
X1216617D01*
Y883420D01*
X1218817D01*
Y892520D01*
G37*
G36*
G01X1221967D02*
X1219767D01*
Y883420D01*
X1221967D01*
Y892520D01*
G37*
G36*
G01X1225116D02*
X1222916D01*
Y883420D01*
X1225116D01*
Y892520D01*
G37*
G36*
G01X1228266D02*
X1226066D01*
Y883420D01*
X1228266D01*
Y892520D01*
G37*
G36*
G01X1231415D02*
X1229215D01*
Y883420D01*
X1231415D01*
Y892520D01*
G37*
G36*
G01X1234565D02*
X1232365D01*
Y883420D01*
X1234565D01*
Y892520D01*
G37*
G36*
G01X1237715D02*
X1235515D01*
Y883420D01*
X1237715D01*
Y892520D01*
G37*
G36*
G01X1240864D02*
X1238664D01*
Y883420D01*
X1240864D01*
Y892520D01*
G37*
G36*
G01X1244014D02*
X1241814D01*
Y883420D01*
X1244014D01*
Y892520D01*
G37*
G36*
G01X1247163D02*
X1244963D01*
Y883420D01*
X1247163D01*
Y892520D01*
G37*
G36*
G01X1250313D02*
X1248113D01*
Y883420D01*
X1250313D01*
Y892520D01*
G37*
G36*
G01X1253463D02*
X1251263D01*
Y883420D01*
X1253463D01*
Y892520D01*
G37*
G36*
G01X1256612D02*
X1254412D01*
Y883420D01*
X1256612D01*
Y892520D01*
G37*
G36*
G01X1259762D02*
X1257562D01*
Y883420D01*
X1259762D01*
Y892520D01*
G37*
G36*
G01X1262912D02*
X1260712D01*
Y883420D01*
X1262912D01*
Y892520D01*
G37*
G36*
G01X1266061D02*
X1263861D01*
Y883420D01*
X1266061D01*
Y892520D01*
G37*
G36*
G01X1269211D02*
X1267011D01*
Y883420D01*
X1269211D01*
Y892520D01*
G37*
G36*
G01X1272360D02*
X1270160D01*
Y883420D01*
X1272360D01*
Y892520D01*
G37*
G36*
G01X1275510D02*
X1273310D01*
Y883420D01*
X1275510D01*
Y892520D01*
G37*
G36*
G01X1278660D02*
X1276460D01*
Y883420D01*
X1278660D01*
Y892520D01*
G37*
G36*
G01X1281809D02*
X1279609D01*
Y883420D01*
X1281809D01*
Y892520D01*
G37*
G36*
G01X1284959D02*
X1282759D01*
Y883420D01*
X1284959D01*
Y892520D01*
G37*
G36*
G01X1288108D02*
X1285908D01*
Y883420D01*
X1288108D01*
Y892520D01*
G37*
G36*
G01X1291258D02*
X1289058D01*
Y883420D01*
X1291258D01*
Y892520D01*
G37*
G36*
G01X1294408D02*
X1292208D01*
Y883420D01*
X1294408D01*
Y892520D01*
G37*
G36*
G01X1297557D02*
X1295357D01*
Y883420D01*
X1297557D01*
Y892520D01*
G37*
G36*
G01X1300707D02*
X1298507D01*
Y883420D01*
X1300707D01*
Y892520D01*
G37*
G36*
G01X1303856D02*
X1301656D01*
Y883420D01*
X1303856D01*
Y892520D01*
G37*
G36*
G01X1307006D02*
X1304806D01*
Y883420D01*
X1307006D01*
Y892520D01*
G37*
G36*
G01X1310156D02*
X1307956D01*
Y883420D01*
X1310156D01*
Y892520D01*
G37*
G36*
G01X1313305D02*
X1311105D01*
Y883420D01*
X1313305D01*
Y892520D01*
G37*
G36*
G01X1316455D02*
X1314255D01*
Y883420D01*
X1316455D01*
Y892520D01*
G37*
G36*
G01X1319604D02*
X1317404D01*
Y883420D01*
X1319604D01*
Y892520D01*
G37*
G36*
G01X1322754D02*
X1320554D01*
Y883420D01*
X1322754D01*
Y892520D01*
G37*
G36*
G01X1325904D02*
X1323704D01*
Y883420D01*
X1325904D01*
Y892520D01*
G37*
G36*
G01X1329053D02*
X1326853D01*
Y883420D01*
X1329053D01*
Y892520D01*
G37*
G36*
G01X1332203D02*
X1330003D01*
Y883420D01*
X1332203D01*
Y892520D01*
G37*
G36*
G01X1335352D02*
X1333152D01*
Y883420D01*
X1335352D01*
Y892520D01*
G37*
G36*
G01X1338502D02*
X1336302D01*
Y883420D01*
X1338502D01*
Y892520D01*
G37*
G36*
G01X1341652D02*
X1339452D01*
Y883420D01*
X1341652D01*
Y892520D01*
G37*
G36*
G01X1344801D02*
X1342601D01*
Y883420D01*
X1344801D01*
Y892520D01*
G37*
G36*
G01X1347951D02*
X1345751D01*
Y883420D01*
X1347951D01*
Y892520D01*
G37*
G36*
G01X1351100D02*
X1348900D01*
Y883420D01*
X1351100D01*
Y892520D01*
G37*
G36*
G01X1354250D02*
X1352050D01*
Y883420D01*
X1354250D01*
Y892520D01*
G37*
G54D10*
G01X127746Y-260199D02*
X95746D01*
G01X127746Y-276199D02*
Y-356199D01*
G01D02*
X1310146D01*
G01X127746Y-311699D02*
X1310146D01*
G01X123746Y-260199D02*
G02I-12000J0D01*
G01X118596D02*
G02I-6850J0D01*
G01X111746Y-276199D02*
Y-244199D01*
G01X127746Y-276199D02*
X1310146D01*
G01X522646D02*
Y-356199D01*
G01X660146Y-276199D02*
Y-356199D01*
G01X775146Y-276199D02*
Y-356199D01*
G01X942646Y-276199D02*
Y-356199D01*
G01X1112646Y-276199D02*
Y-356199D01*
G01X1310146Y-276199D02*
Y-356199D01*
G01X1342146Y-260199D02*
X1310146D01*
G01X1338146D02*
G02I-12000J0D01*
G01X1332996D02*
G02I-6850J0D01*
G01X1326146Y-276199D02*
Y-244199D01*
G54D11*
G01X145579Y-328699D02*
Y-346199D01*
X154313D01*
G01X167446Y-334533D02*
Y-346199D01*
G01Y-329866D02*
X167009Y-329574D01*
Y-328991D01*
X167446Y-328699D01*
X167883Y-328991D01*
Y-329574D01*
X167446Y-329866D01*
G01X181889Y-350574D02*
X183418Y-351741D01*
X185164Y-352032D01*
X186692Y-351741D01*
X188003Y-350283D01*
X188876Y-348241D01*
Y-334533D01*
G01Y-336866D02*
X188003Y-335699D01*
X186692Y-334824D01*
X185164Y-334533D01*
X183418Y-335116D01*
X182326Y-336282D01*
X181452Y-338324D01*
X181016Y-340366D01*
X181234Y-342116D01*
X182108Y-344158D01*
X183418Y-345616D01*
X185164Y-346199D01*
X186474Y-345907D01*
X188003Y-344741D01*
X188876Y-343575D01*
G01X198734Y-346199D02*
Y-328699D01*
G01Y-337157D02*
X199826Y-335699D01*
X200918Y-334824D01*
X202664Y-334533D01*
X203974Y-334824D01*
X205503Y-335991D01*
X206158Y-337741D01*
Y-346199D01*
G01X219946Y-328699D02*
Y-346199D01*
G01X216889Y-334533D02*
X223003D01*
G01X233734Y-346199D02*
Y-334533D01*
G01Y-337449D02*
X234608Y-335991D01*
X235918Y-334824D01*
X237664Y-334533D01*
X239192Y-334824D01*
X240503Y-335991D01*
X241158Y-338032D01*
Y-346199D01*
G01X254946Y-334533D02*
Y-346199D01*
G01Y-329866D02*
X254509Y-329574D01*
Y-328991D01*
X254946Y-328699D01*
X255383Y-328991D01*
Y-329574D01*
X254946Y-329866D01*
G01X268734Y-346199D02*
Y-334533D01*
G01Y-337449D02*
X269608Y-335991D01*
X270918Y-334824D01*
X272664Y-334533D01*
X274192Y-334824D01*
X275503Y-335991D01*
X276158Y-338032D01*
Y-346199D01*
G01X286889Y-350574D02*
X288418Y-351741D01*
X290164Y-352032D01*
X291692Y-351741D01*
X293003Y-350283D01*
X293876Y-348241D01*
Y-334533D01*
G01Y-336866D02*
X293003Y-335699D01*
X291692Y-334824D01*
X290164Y-334533D01*
X288418Y-335116D01*
X287326Y-336282D01*
X286452Y-338324D01*
X286016Y-340366D01*
X286234Y-342116D01*
X287108Y-344158D01*
X288418Y-345616D01*
X290164Y-346199D01*
X291474Y-345907D01*
X293003Y-344741D01*
X293876Y-343575D01*
G01X320579Y-346199D02*
Y-328699D01*
X325819D01*
X327566Y-329574D01*
X328876Y-331616D01*
X329313Y-333949D01*
X328876Y-336282D01*
X327784Y-338032D01*
X325819Y-338908D01*
X320579D01*
G01X346813Y-346199D02*
X338079D01*
Y-328699D01*
X346813D01*
G01X343319Y-337157D02*
X338079D01*
G01X361692Y-336866D02*
X362566Y-335991D01*
X363221Y-334533D01*
X363658Y-332490D01*
X363221Y-330741D01*
X362348Y-329574D01*
X360819Y-328699D01*
X354924D01*
Y-346199D01*
X362129D01*
X363658Y-345033D01*
X364531Y-343282D01*
X364968Y-341241D01*
X364531Y-339199D01*
X363221Y-337449D01*
X361692Y-336866D01*
X354924D01*
G01X390579Y-346199D02*
Y-328699D01*
X395819D01*
X397566Y-329574D01*
X398876Y-331616D01*
X399313Y-333949D01*
X398876Y-336282D01*
X397784Y-338032D01*
X395819Y-338908D01*
X390579D01*
G01X406769Y-346199D02*
Y-328699D01*
X412446Y-343282D01*
X418123Y-328699D01*
Y-346199D01*
G01X434749Y-330158D02*
X433439Y-329282D01*
X431911Y-328699D01*
X430164D01*
X428199Y-329574D01*
X426671Y-331032D01*
X425579Y-332783D01*
X424706Y-335699D01*
X424487Y-338324D01*
X424924Y-340949D01*
X425579Y-342699D01*
X426889Y-344449D01*
X428418Y-345616D01*
X429946Y-346199D01*
X431474D01*
X433003Y-345616D01*
X434313Y-344741D01*
X435405Y-343575D01*
G01X460579Y-346199D02*
Y-328699D01*
X465819D01*
X467566Y-329574D01*
X468876Y-331616D01*
X469313Y-333949D01*
X468876Y-336282D01*
X467784Y-338032D01*
X465819Y-338908D01*
X460579D01*
G01X476987Y-328699D02*
X482446Y-346199D01*
X487905Y-328699D01*
G01X499946D02*
Y-346199D01*
G01X494924Y-328699D02*
X504968D01*
G01X284269Y-301199D02*
Y-283699D01*
X289946Y-298282D01*
X295623Y-283699D01*
Y-301199D01*
G01X307446D02*
X306136Y-300907D01*
X304826Y-299741D01*
X303952Y-297699D01*
X303516Y-295366D01*
X303952Y-293032D01*
X304826Y-290991D01*
X306136Y-289824D01*
X307446Y-289533D01*
X308756Y-289824D01*
X310066Y-290991D01*
X310939Y-293032D01*
X311158Y-295366D01*
X310939Y-297699D01*
X310066Y-299741D01*
X308756Y-300907D01*
X307446Y-301199D01*
G01X328876Y-283699D02*
Y-301199D01*
G01Y-298575D02*
X328003Y-300033D01*
X326692Y-300907D01*
X325164Y-301199D01*
X323418Y-300616D01*
X322108Y-299158D01*
X321234Y-297408D01*
X321016Y-295366D01*
X321234Y-293324D01*
X322108Y-291574D01*
X323418Y-290116D01*
X325164Y-289533D01*
X326692Y-289824D01*
X327784Y-290408D01*
X328876Y-291574D01*
G01X339171Y-293324D02*
X346158D01*
X345503Y-291282D01*
X344411Y-290116D01*
X342883Y-289533D01*
X341354Y-289824D01*
X340044Y-290699D01*
X339171Y-292741D01*
X338734Y-294491D01*
Y-296241D01*
X339171Y-297991D01*
X340263Y-299741D01*
X341573Y-300907D01*
X343101Y-301199D01*
X344629Y-300616D01*
X346158Y-298866D01*
G01X359946Y-301199D02*
Y-283699D01*
G01X556346Y-346199D02*
Y-328699D01*
X553726Y-332199D01*
G01Y-346199D02*
X558966D01*
G01X569043Y-343575D02*
X570352Y-345033D01*
X571881Y-345907D01*
X573846Y-346199D01*
X575811Y-345616D01*
X577339Y-344449D01*
X578431Y-342408D01*
X578649Y-340074D01*
X578213Y-337741D01*
X577121Y-336282D01*
X575592Y-335116D01*
X574064Y-334824D01*
X572536Y-335116D01*
X570571Y-336282D01*
X571226Y-328699D01*
X577121D01*
G01X591346Y-346199D02*
Y-328699D01*
X588726Y-332199D01*
G01Y-346199D02*
X593966D01*
G01X608846Y-328699D02*
X607099Y-329282D01*
X605789Y-330741D01*
X604916Y-332490D01*
X604261Y-334824D01*
X604043Y-337449D01*
X604261Y-340074D01*
X604916Y-342408D01*
X605789Y-344158D01*
X607099Y-345616D01*
X608846Y-346199D01*
X610592Y-345616D01*
X611903Y-344158D01*
X612776Y-342408D01*
X613431Y-340074D01*
X613649Y-337449D01*
X613431Y-334824D01*
X612776Y-332490D01*
X611903Y-330741D01*
X610592Y-329282D01*
X608846Y-328699D01*
G01X621543Y-343575D02*
X622852Y-345033D01*
X624381Y-345907D01*
X626346Y-346199D01*
X628311Y-345616D01*
X629839Y-344449D01*
X630931Y-342408D01*
X631149Y-340074D01*
X630713Y-337741D01*
X629621Y-336282D01*
X628092Y-335116D01*
X626564Y-334824D01*
X625036Y-335116D01*
X623071Y-336282D01*
X623726Y-328699D01*
X629621D01*
G01X543229Y-301199D02*
Y-283699D01*
X548469D01*
X550216Y-284574D01*
X551526Y-286616D01*
X551963Y-288949D01*
X551526Y-291282D01*
X550434Y-293032D01*
X548469Y-293908D01*
X543229D01*
G01X569899Y-285158D02*
X568589Y-284282D01*
X567061Y-283699D01*
X565314D01*
X563349Y-284574D01*
X561821Y-286032D01*
X560729Y-287783D01*
X559856Y-290699D01*
X559637Y-293324D01*
X560074Y-295949D01*
X560729Y-297699D01*
X562039Y-299449D01*
X563568Y-300616D01*
X565096Y-301199D01*
X566624D01*
X568153Y-300616D01*
X569463Y-299741D01*
X570555Y-298575D01*
G01X584342Y-291866D02*
X585216Y-290991D01*
X585871Y-289533D01*
X586308Y-287490D01*
X585871Y-285741D01*
X584998Y-284574D01*
X583469Y-283699D01*
X577574D01*
Y-301199D01*
X584779D01*
X586308Y-300033D01*
X587181Y-298282D01*
X587618Y-296241D01*
X587181Y-294199D01*
X585871Y-292449D01*
X584342Y-291866D01*
X577574D01*
G01X593546Y-307032D02*
X606646D01*
G01X612574Y-301199D02*
Y-283699D01*
X622618Y-301199D01*
Y-283699D01*
G01X635096Y-301199D02*
X633349Y-300907D01*
X631821Y-299741D01*
X630511Y-297991D01*
X629637Y-295949D01*
X629201Y-293616D01*
Y-291282D01*
X629637Y-288949D01*
X630511Y-286907D01*
X631821Y-285158D01*
X633349Y-283991D01*
X635096Y-283699D01*
X636842Y-283991D01*
X638371Y-285158D01*
X639681Y-286907D01*
X640555Y-288949D01*
X640991Y-291282D01*
Y-293616D01*
X640555Y-295949D01*
X639681Y-297991D01*
X638371Y-299741D01*
X636842Y-300907D01*
X635096Y-301199D01*
G01X685937Y-283699D02*
X691396Y-301199D01*
X696855Y-283699D01*
G01X713263Y-301199D02*
X704529D01*
Y-283699D01*
X713263D01*
G01X709769Y-292157D02*
X704529D01*
G01X722029Y-301199D02*
Y-283699D01*
X727488D01*
X729234Y-284574D01*
X730326Y-285741D01*
X730763Y-288074D01*
X730326Y-290408D01*
X729016Y-291866D01*
X727488Y-292741D01*
X722029D01*
G01X727488D02*
X730763Y-301199D01*
G01X743896Y-301782D02*
X743459Y-301491D01*
Y-300907D01*
X743896Y-300616D01*
X744333Y-300907D01*
Y-301491D01*
X743896Y-301782D01*
G01X717646Y-346199D02*
Y-328699D01*
X715026Y-332199D01*
G01Y-346199D02*
X720266D01*
G01X901286Y-337449D02*
X896919D01*
Y-342699D01*
X898229Y-344449D01*
X899758Y-345616D01*
X901941Y-346199D01*
X904124Y-345616D01*
X905653Y-344449D01*
X906963Y-342699D01*
X907836Y-340657D01*
X908273Y-338324D01*
Y-336282D01*
X907836Y-334533D01*
X906963Y-332490D01*
X905653Y-330741D01*
X904343Y-329574D01*
X902596Y-328699D01*
X901068D01*
X899321Y-329282D01*
X898011Y-330449D01*
G01X885096Y-346199D02*
X886843Y-345907D01*
X888371Y-344741D01*
X889681Y-342991D01*
X890555Y-340949D01*
X890991Y-338616D01*
Y-336282D01*
X890555Y-333949D01*
X889681Y-331907D01*
X888371Y-330158D01*
X886843Y-328991D01*
X885096Y-328699D01*
X883350Y-328991D01*
X881821Y-330158D01*
X880511Y-331907D01*
X879637Y-333949D01*
X879201Y-336282D01*
Y-338616D01*
X879637Y-340949D01*
X880511Y-342991D01*
X881821Y-344741D01*
X883350Y-345907D01*
X885096Y-346199D01*
G01X871963Y-328699D02*
Y-346199D01*
X863229D01*
G01X854899D02*
Y-328699D01*
X850533D01*
X848786Y-329574D01*
X847476Y-330741D01*
X846384Y-332490D01*
X845511Y-334533D01*
X845293Y-337449D01*
X845511Y-340366D01*
X846384Y-342408D01*
X847476Y-344158D01*
X848786Y-345324D01*
X850533Y-346199D01*
X854899D01*
G01X839146Y-352032D02*
X826046D01*
G01X813350Y-336866D02*
X812476Y-335991D01*
X811821Y-334533D01*
X811384Y-332490D01*
X811821Y-330741D01*
X812694Y-329574D01*
X814223Y-328699D01*
X820118D01*
Y-346199D01*
X812913D01*
X811384Y-345033D01*
X810511Y-343282D01*
X810074Y-341241D01*
X810511Y-339199D01*
X811821Y-337449D01*
X813350Y-336866D01*
X820118D01*
G01X819479Y-283699D02*
Y-301199D01*
X828213D01*
G01X845276D02*
Y-289533D01*
G01Y-291574D02*
X844403Y-290408D01*
X843092Y-289824D01*
X841564Y-289533D01*
X840036Y-290116D01*
X838726Y-291282D01*
X837852Y-293032D01*
X837416Y-295366D01*
X837852Y-297699D01*
X838726Y-299449D01*
X840036Y-300616D01*
X841564Y-301199D01*
X843092Y-300907D01*
X844403Y-300033D01*
X845276Y-298866D01*
G01X854261Y-306449D02*
X855571Y-307032D01*
X857318Y-306449D01*
X858409Y-305283D01*
X859283Y-303824D01*
X860592Y-299158D01*
X863431Y-289533D01*
G01X856444D02*
X860592Y-299158D01*
G01X873071Y-293324D02*
X880058D01*
X879403Y-291282D01*
X878311Y-290116D01*
X876783Y-289533D01*
X875254Y-289824D01*
X873944Y-290699D01*
X873071Y-292741D01*
X872634Y-294491D01*
Y-296241D01*
X873071Y-297991D01*
X874163Y-299741D01*
X875473Y-300907D01*
X877001Y-301199D01*
X878529Y-300616D01*
X880058Y-298866D01*
G01X890789Y-301199D02*
Y-289533D01*
G01Y-291866D02*
X891881Y-290699D01*
X892973Y-289824D01*
X894501Y-289533D01*
X895592Y-289824D01*
X896903Y-290699D01*
G01X959846Y-328699D02*
X962902Y-346199D01*
X966396Y-328699D01*
X969889Y-346199D01*
X972946Y-328699D01*
G01X979529Y-346199D02*
Y-328699D01*
X984769D01*
X986516Y-329574D01*
X987826Y-331616D01*
X988263Y-333949D01*
X987826Y-336282D01*
X986734Y-338032D01*
X984769Y-338908D01*
X979529D01*
G01X996811Y-346199D02*
Y-328699D01*
G01X1005981D02*
Y-346199D01*
G01Y-337449D02*
X996811D01*
G01X1016058Y-340366D02*
X1021734D01*
G01X1031593Y-346199D02*
Y-328699D01*
G01X1039889D02*
X1031593Y-339491D01*
G01X1041199Y-346199D02*
X1035304Y-334533D01*
G01X1058263Y-346199D02*
X1049529D01*
Y-328699D01*
X1058263D01*
G01X1054769Y-337157D02*
X1049529D01*
G01X1066374Y-346199D02*
Y-328699D01*
X1076418Y-346199D01*
Y-328699D01*
G01X1083874Y-346199D02*
Y-328699D01*
X1093918Y-346199D01*
Y-328699D01*
G01X961593Y-301199D02*
Y-283699D01*
X965959D01*
X967706Y-284574D01*
X969016Y-285741D01*
X970108Y-287490D01*
X970981Y-289533D01*
X971199Y-292449D01*
X970981Y-295366D01*
X970108Y-297408D01*
X969016Y-299158D01*
X967706Y-300324D01*
X965959Y-301199D01*
X961593D01*
G01X980621Y-293324D02*
X987608D01*
X986953Y-291282D01*
X985861Y-290116D01*
X984333Y-289533D01*
X982804Y-289824D01*
X981494Y-290699D01*
X980621Y-292741D01*
X980184Y-294491D01*
Y-296241D01*
X980621Y-297991D01*
X981713Y-299741D01*
X983023Y-300907D01*
X984551Y-301199D01*
X986079Y-300616D01*
X987608Y-298866D01*
G01X998121Y-299158D02*
X999213Y-300324D01*
X1000741Y-301199D01*
X1002051D01*
X1003361Y-300616D01*
X1004234Y-299741D01*
X1004671Y-298575D01*
X1004453Y-296824D01*
X1003579Y-295949D01*
X999649Y-294199D01*
X998776Y-292157D01*
X999213Y-290699D01*
X1000086Y-289824D01*
X1001396Y-289533D01*
X1002706Y-289824D01*
X1004016Y-290699D01*
G01X1018896Y-289533D02*
Y-301199D01*
G01Y-284866D02*
X1018459Y-284574D01*
Y-283991D01*
X1018896Y-283699D01*
X1019333Y-283991D01*
Y-284574D01*
X1018896Y-284866D01*
G01X1033339Y-305574D02*
X1034868Y-306741D01*
X1036614Y-307032D01*
X1038142Y-306741D01*
X1039453Y-305283D01*
X1040326Y-303241D01*
Y-289533D01*
G01Y-291866D02*
X1039453Y-290699D01*
X1038142Y-289824D01*
X1036614Y-289533D01*
X1034868Y-290116D01*
X1033776Y-291282D01*
X1032902Y-293324D01*
X1032466Y-295366D01*
X1032684Y-297116D01*
X1033558Y-299158D01*
X1034868Y-300616D01*
X1036614Y-301199D01*
X1037924Y-300907D01*
X1039453Y-299741D01*
X1040326Y-298575D01*
G01X1050184Y-301199D02*
Y-289533D01*
G01Y-292449D02*
X1051058Y-290991D01*
X1052368Y-289824D01*
X1054114Y-289533D01*
X1055642Y-289824D01*
X1056953Y-290991D01*
X1057608Y-293032D01*
Y-301199D01*
G01X1068121Y-293324D02*
X1075108D01*
X1074453Y-291282D01*
X1073361Y-290116D01*
X1071833Y-289533D01*
X1070304Y-289824D01*
X1068994Y-290699D01*
X1068121Y-292741D01*
X1067684Y-294491D01*
Y-296241D01*
X1068121Y-297991D01*
X1069213Y-299741D01*
X1070523Y-300907D01*
X1072051Y-301199D01*
X1073579Y-300616D01*
X1075108Y-298866D01*
G01X1085839Y-301199D02*
Y-289533D01*
G01Y-291866D02*
X1086931Y-290699D01*
X1088023Y-289824D01*
X1089551Y-289533D01*
X1090642Y-289824D01*
X1091953Y-290699D01*
G01X1132596Y-346199D02*
Y-328699D01*
X1129976Y-332199D01*
G01Y-346199D02*
X1135216D01*
G01X1150096D02*
Y-328699D01*
X1147476Y-332199D01*
G01Y-346199D02*
X1152716D01*
G01X1163666Y-346782D02*
X1171526Y-328699D01*
G01X1185096Y-346199D02*
Y-328699D01*
X1182476Y-332199D01*
G01Y-346199D02*
X1187716D01*
G01X1198448Y-338908D02*
X1199976Y-336866D01*
X1201286Y-335699D01*
X1203033Y-335116D01*
X1204561Y-335699D01*
X1205653Y-336866D01*
X1206526Y-338616D01*
X1206744Y-340657D01*
X1206526Y-342408D01*
X1205653Y-344158D01*
X1204342Y-345616D01*
X1202814Y-346199D01*
X1201068Y-345616D01*
X1199539Y-343866D01*
X1198666Y-341241D01*
X1198448Y-338324D01*
X1198884Y-334533D01*
X1199539Y-332490D01*
X1200631Y-330449D01*
X1202159Y-328991D01*
X1203688Y-328699D01*
X1205216Y-329282D01*
X1206308Y-330741D01*
G01X1216166Y-346782D02*
X1224026Y-328699D01*
G01X1233448Y-331616D02*
X1234758Y-329866D01*
X1236286Y-328991D01*
X1238033Y-328699D01*
X1240216Y-329282D01*
X1241744Y-330741D01*
X1242181Y-332490D01*
X1241963Y-334241D01*
X1241089Y-335699D01*
X1236723Y-338616D01*
X1234758Y-340657D01*
X1233448Y-343575D01*
X1233011Y-346199D01*
X1242181D01*
G01X1255096Y-328699D02*
X1253349Y-329282D01*
X1252039Y-330741D01*
X1251166Y-332490D01*
X1250511Y-334824D01*
X1250293Y-337449D01*
X1250511Y-340074D01*
X1251166Y-342408D01*
X1252039Y-344158D01*
X1253349Y-345616D01*
X1255096Y-346199D01*
X1256842Y-345616D01*
X1258153Y-344158D01*
X1259026Y-342408D01*
X1259681Y-340074D01*
X1259899Y-337449D01*
X1259681Y-334824D01*
X1259026Y-332490D01*
X1258153Y-330741D01*
X1256842Y-329282D01*
X1255096Y-328699D01*
G01X1272596Y-346199D02*
Y-328699D01*
X1269976Y-332199D01*
G01Y-346199D02*
X1275216D01*
G01X1285948Y-338908D02*
X1287476Y-336866D01*
X1288786Y-335699D01*
X1290533Y-335116D01*
X1292061Y-335699D01*
X1293153Y-336866D01*
X1294026Y-338616D01*
X1294244Y-340657D01*
X1294026Y-342408D01*
X1293153Y-344158D01*
X1291842Y-345616D01*
X1290314Y-346199D01*
X1288568Y-345616D01*
X1287039Y-343866D01*
X1286166Y-341241D01*
X1285948Y-338324D01*
X1286384Y-334533D01*
X1287039Y-332490D01*
X1288131Y-330449D01*
X1289659Y-328991D01*
X1291188Y-328699D01*
X1292716Y-329282D01*
X1293808Y-330741D01*
G01X1180293Y-301199D02*
Y-283699D01*
X1184659D01*
X1186406Y-284574D01*
X1187716Y-285741D01*
X1188808Y-287490D01*
X1189681Y-289533D01*
X1189899Y-292449D01*
X1189681Y-295366D01*
X1188808Y-297408D01*
X1187716Y-299158D01*
X1186406Y-300324D01*
X1184659Y-301199D01*
X1180293D01*
G01X1206526D02*
Y-289533D01*
G01Y-291574D02*
X1205653Y-290408D01*
X1204342Y-289824D01*
X1202814Y-289533D01*
X1201286Y-290116D01*
X1199976Y-291282D01*
X1199102Y-293032D01*
X1198666Y-295366D01*
X1199102Y-297699D01*
X1199976Y-299449D01*
X1201286Y-300616D01*
X1202814Y-301199D01*
X1204342Y-300907D01*
X1205653Y-300033D01*
X1206526Y-298866D01*
G01X1220096Y-283699D02*
Y-301199D01*
G01X1217039Y-289533D02*
X1223153D01*
G01X1234321Y-293324D02*
X1241308D01*
X1240653Y-291282D01*
X1239561Y-290116D01*
X1238033Y-289533D01*
X1236504Y-289824D01*
X1235194Y-290699D01*
X1234321Y-292741D01*
X1233884Y-294491D01*
Y-296241D01*
X1234321Y-297991D01*
X1235413Y-299741D01*
X1236723Y-300907D01*
X1238251Y-301199D01*
X1239779Y-300616D01*
X1241308Y-298866D01*
G01X1425733Y-51181D02*
X-29385D01*
G01X-33322Y-47244D02*
G03X-29385Y-51181I3937J0D01*
G01X-33322Y-47244D02*
Y893701D01*
G01X-7874Y102402D02*
Y212205D01*
G01Y102402D02*
G03X0Y94528I7874J0D01*
G01Y212205D02*
G03X-7874I-3937J0D01*
G01Y237402D02*
G03X0I3937J-1D01*
G01X-7874D02*
Y406693D01*
G01X0D02*
G03X-7874I-3937J0D01*
G01Y431890D02*
G03X0I3937J0D01*
G01X-7874D02*
Y601181D01*
G01X0D02*
G03X-7874I-3937J0D01*
G01Y626378D02*
Y795669D01*
G01Y626378D02*
G03X0I3937J0D01*
G01Y795669D02*
G03X-7874I-3937J0D01*
G01Y820866D02*
G03X0I3937J0D01*
G01X-7874Y844488D02*
Y820866D01*
G01X-3937Y848425D02*
G03X-7874Y844488I0J-3937D01*
G01X93307Y848425D02*
X-3937D01*
G01X-29385Y897638D02*
G03X-33322Y893701I0J-3937D01*
G01X-29385Y897638D02*
X93307D01*
G01X98425Y94528D02*
X0D01*
G01X1400000Y36220D02*
G03X1398031Y38189I-1969J0D01*
G01X1396654D01*
G02X1394685Y40157I0J1969D01*
G01Y71654D01*
G02X1396654Y73622I1969J-1D01*
G01X1398031D01*
G03X1400000Y75591I0J1969D01*
G01Y836614D01*
G03X1396063Y840551I-3937J0D01*
G01X1368504D01*
G02X1363386Y845669I0J5118D01*
G01Y871654D01*
G03X1361417Y873622I-1969J-1D01*
G01X1358268D01*
G02X1356299Y875591I0J1969D01*
G01Y892521D01*
X1352363Y897638D01*
X1218110D01*
X1214173Y892520D01*
Y875984D01*
G02X1205512I-4331J0D01*
G01Y892520D01*
X1201575Y897638D01*
X1029528D01*
X1025591Y892520D01*
Y875591D01*
G02X1023622Y873622I-1969J0D01*
G01X1020472D01*
G03X1018504Y871654I0J-1968D01*
G01Y845669D01*
G02X1013386Y840551I-5118J0D01*
G01X1008433D01*
G03X988748Y820866I0J-19685D01*
G01Y650669D01*
G02X983748Y645669I-5000J0D01*
G01X926819D01*
G02X921819Y650669I0J5000D01*
G01Y820866D01*
G03X902134Y840551I-19685J0D01*
G01X872441D01*
G02X867323Y845669I0J5118D01*
G01Y871654D01*
G03X865354Y873622I-1969J-1D01*
G01X862205D01*
G02X860236Y875591I0J1969D01*
G01Y892521D01*
X856300Y897638D01*
X722048D01*
X718110Y892519D01*
Y875984D01*
G02X709449I-4331J0D01*
G01Y892520D01*
X705512Y897638D01*
X533465D01*
X529528Y892520D01*
Y875591D01*
G02X527559Y873622I-1969J0D01*
G01X524409D01*
G03X522441Y871654I0J-1968D01*
G01Y845669D01*
G02X517323Y840551I-5118J0D01*
G01X455118D01*
G02X450000Y845669I0J5118D01*
G01Y871654D01*
G03X448031Y873622I-1968J0D01*
G01X444882D01*
G02X442913Y875591I0J1969D01*
G01Y892521D01*
X438977Y897638D01*
X304725D01*
X300787Y892519D01*
Y875984D01*
G02X292126I-4331J0D01*
G01Y892521D01*
X288190Y897638D01*
X116142D01*
X112205Y892520D01*
Y875591D01*
G02X110236Y873622I-1969J0D01*
G01X107087D01*
G03X105118Y871654I0J-1969D01*
G01Y845669D01*
G02X100000Y840551I-5118J0D01*
G01X3937D01*
G03X0Y836614I0J-3937D01*
G01Y110276D01*
G03X7874Y102402I7874J0D01*
G01X196654D01*
G02X204528Y94528I0J-7874D01*
G01Y7874D01*
G03X212402Y0I7874J0D01*
G01X471014D01*
G02X478888Y-7874I0J-7874D01*
G01Y-11811D01*
G03X486762Y-19685I7874J0D01*
G01X1302165D01*
G03X1306102Y-15748I0J3937D01*
G01Y-3937D01*
G02X1310039Y0I3937J0D01*
G01X1396063D01*
G03X1400000Y3937I0J3937D01*
G01Y36220D01*
G01X93307Y848425D02*
G03X97244Y852362I0J3937D01*
G01Y893701D02*
Y852362D01*
G01Y893701D02*
G03X93307Y897638I-3937J0D01*
G01X192717Y94528D02*
X123622D01*
G01Y102402D02*
G03Y94528I0J-3937D01*
G01X98425D02*
G03Y102402I0J3937D01*
G01X196654Y0D02*
G03X204528Y-7874I7874J0D01*
G01X196654Y0D02*
Y29961D01*
G01X204528D02*
G03X196654I-3937J0D01*
G01Y55157D02*
Y90591D01*
G01Y55157D02*
G03X204528I3937J0D01*
G01X196654Y90591D02*
G03X192717Y94528I-3937J0D01*
G01X232077Y-7874D02*
G03Y0I0J3937D01*
G01Y-7874D02*
X204528D01*
G01X434439D02*
X257274D01*
G01Y0D02*
G03Y-7874I0J-3937D01*
G01X365945Y38188D02*
G03X367914Y40156I0J1969D01*
G01X354134D02*
G03X356103Y38188I1969J1D01*
G01D02*
X365945D01*
G01X354134Y71653D02*
Y40156D01*
G01X367914Y71653D02*
G03X365945Y73621I-1969J-1D01*
G01X356103D02*
G03X354134Y71653I0J-1969D01*
G01X365945Y73621D02*
X356103D01*
G01X367914Y40156D02*
Y71653D01*
G01X434439Y-7874D02*
G03Y0I0J3937D01*
G01X471014Y-15748D02*
G03X463140Y-7874I-7874J0D01*
G01D02*
X459636D01*
G01Y0D02*
G03Y-7874I0J-3937D01*
G01X707234Y-27559D02*
X478888D01*
G01X471014Y-19685D02*
G03X478888Y-27559I7874J0D01*
G01X471014Y-19685D02*
Y-15748D01*
G01X870226Y-27559D02*
X732431D01*
G01Y-19685D02*
G03Y-27559I0J-3937D01*
G01X707234D02*
G03Y-19685I0J3937D01*
G01X870226Y-27559D02*
G03Y-19685I1J3937D01*
G01X1072589Y-27559D02*
X895423D01*
G01Y-19685D02*
G03Y-27559I0J-3937D01*
G01X1072589D02*
G03Y-19685I0J3937D01*
G01X1097785D02*
G03Y-27559I1J-3937D01*
G01X1336086Y-8662D02*
X1318701D01*
G03X1314764Y-12599I0J-3937D01*
G01Y-23622D01*
G02X1310827Y-27559I-3937J0D01*
G01X1097785D01*
G01X1336086Y-8662D02*
G03Y-1I0J4330D01*
G01X1361283D02*
G03Y-8662I0J-4330D01*
G01X1407874Y13026D02*
Y-4725D01*
G02X1403937Y-8662I-3937J0D01*
G01X1361283D01*
G01X1403937Y848425D02*
X1375197D01*
G01X1371260Y852362D02*
G03X1375197Y848425I3937J0D01*
G01X1371260Y852362D02*
Y893701D01*
G01X1375197Y897638D02*
G03X1371260Y893701I0J-3937D01*
G01X1375197Y897638D02*
X1425733D01*
G01X1407874Y30709D02*
Y219685D01*
G01X1400000Y30709D02*
G03X1407874I3937J0D01*
G01Y13026D02*
G03X1400000I-3937J-1D01*
G01X1407874Y219685D02*
G03X1400000I-3937J0D01*
G01Y244882D02*
G03X1407874I3937J0D01*
G01Y414173D02*
Y244882D01*
G01Y608661D02*
Y439370D01*
G01X1400000D02*
G03X1407874I3937J0D01*
G01Y414173D02*
G03X1400000I-3937J0D01*
G01X1407874Y608661D02*
G03X1400000I-3937J0D01*
G01Y626378D02*
G03X1407874I3937J0D01*
G01Y795669D02*
Y626378D01*
G01Y795669D02*
G03X1400000I-3937J0D01*
G01Y820866D02*
G03X1407874I3937J0D01*
G01Y844488D02*
Y820866D01*
G01Y844488D02*
G03X1403937Y848425I-3937J0D01*
G01X1429670Y893701D02*
Y-47244D01*
G01X1425733Y-51181D02*
G03X1429670Y-47244I0J3937D01*
G01Y893701D02*
G03X1425733Y897638I-3937J0D01*
M02*
